# BASEBOARD_FAB2 (Tioga Pass) — schematic netlist excerpt (pin names and nets, part order shuffled) for the footprints in the layout excerpt that follows; sources: Cadence DE-HDL packaged netlist, KiCad conversion of Wiwynn_Tioga_Pass_MB.brd

C7C17  CAP  1.0UF 16V 10% X6S  pkg 0402  page 212 : A = VR_PVCCIO_CPU0_PH1_VCIN ; B = GND
C2D38  CAP_A  22.0UF 4V 20% X6S  pkg 0603V  page 76 : A = PVCCIN_CPU1 ; B = GND
R6W29  RES  10.0K 1% CHIP  pkg 0402  page 89 : A = PVPP_ABC ; B = FM_ADR_COMPLETE_CPU1_N

(kicad_pcb
	(version 20260206)
	(generator "pcbnew")
	(generator_version "10.0")
	(general
		(thickness 1.6)
		(legacy_teardrops no)
	)
	(paper "A4")
	(title_block
		(title "Wiwynn_Tioga_Pass_MB.brd")
		(comment 1 "Tioga Pass / footprints 296-298 of 4770")
	)
	(layers
		(0 "F.Cu" signal "TOP")
		(4 "In1.Cu" signal "L2GND")
		(6 "In2.Cu" signal "L3")
		(8 "In3.Cu" signal "L4GND")
		(10 "In4.Cu" signal "L5")
		(12 "In5.Cu" signal "L6GND")
		(14 "In6.Cu" signal "L7VCC")
		(16 "In7.Cu" signal "L8VCC")
		(18 "In8.Cu" signal "L9GND")
		(20 "In9.Cu" signal "L10")
		(22 "In10.Cu" signal "L11GND")
		(24 "In11.Cu" signal "L12")
		(26 "In12.Cu" signal "L13GND")
		(2 "B.Cu" signal "BOTTOM")
		(9 "F.Adhes" user "F.Adhesive")
		(11 "B.Adhes" user "B.Adhesive")
		(13 "F.Paste" user "Package Geometry/Pastemask Top")
		(15 "B.Paste" user "Package Geometry/Pastemask Bottom")
		(5 "F.SilkS" user "Ref Des/Silkscreen Top")
		(7 "B.SilkS" user "Ref Des/Silkscreen Bottom")
		(1 "F.Mask" user "Board Geometry/Soldermask Top")
		(3 "B.Mask" user "Board Geometry/Soldermask Bottom")
		(17 "Dwgs.User" user "User.Drawings")
		(19 "Cmts.User" user "User.Comments")
		(21 "Eco1.User" user "User.Eco1")
		(23 "Eco2.User" user "User.Eco2")
		(25 "Edge.Cuts" user "Board Geometry/Outline")
		(27 "Margin" user)
		(31 "F.CrtYd" user "Package Geometry/Place Bound Top")
		(29 "B.CrtYd" user "Package Geometry/Place Bound Bottom")
		(35 "F.Fab" user "Ref Des/Assembly Top")
		(33 "B.Fab" user "Ref Des/Assembly Bottom")
	)
	(footprint ""
		(layer "F.Cu")
		(at 103.16464 -73.318116)
		(property "Reference" "C2D38"
			(at 0 0 0)
			(layer "F.SilkS")
			(hide yes)
			(effects
				(font
					(size 1.27 1.27)
				)
			)
		)
		(property "Value" ""
			(at 0 0 0)
			(layer "F.Fab")
			(effects
				(font
					(size 1.27 1.27)
				)
			)
		)
		(duplicate_pad_numbers_are_jumpers no)
		(fp_poly
			(pts
				(xy -0.4953 -0.2032) (xy 0.4953 -0.2032) (xy 0.4953 1.6002) (xy -0.4953 1.6002)
			)
			(stroke
				(width 0)
				(type default)
			)
			(fill no)
			(layer "F.CrtYd")
		)
		(fp_line
			(start -0.4953 -0.2032)
			(end 0.4953 -0.2032)
			(stroke
				(width 0.1)
				(type default)
			)
			(layer "F.Fab")
		)
		(fp_line
			(start -0.4953 1.6002)
			(end -0.4953 -0.2032)
			(stroke
				(width 0.1)
				(type default)
			)
			(layer "F.Fab")
		)
		(fp_line
			(start 0.4953 -0.2032)
			(end 0.4953 1.6002)
			(stroke
				(width 0.1)
				(type default)
			)
			(layer "F.Fab")
		)
		(fp_line
			(start 0.4953 1.6002)
			(end -0.4953 1.6002)
			(stroke
				(width 0.1)
				(type default)
			)
			(layer "F.Fab")
		)
		(pad "1" smd rect
			(at 0 0)
			(size 0.762 0.889)
			(layers "F.Cu" "F.Mask" "F.Paste")
			(net "PVCCIN_CPU1")
		)
		(pad "2" smd rect
			(at 0 1.397)
			(size 0.762 0.889)
			(layers "F.Cu" "F.Mask" "F.Paste")
			(net "GND")
		)
		(zone
			(layer "F.Cu")
			(hatch none 0.5)
			(connect_pads
				(clearance 0)
			)
			(min_thickness 0.25)
			(keepout
				(tracks not_allowed)
				(vias allowed)
				(pads allowed)
				(copperpour not_allowed)
				(footprints allowed)
			)
			(placement
				(enabled no)
				(sheetname "")
			)
			(fill
				(thermal_gap 0.5)
				(thermal_bridge_width 0.5)
				(island_removal_mode 0)
			)
			(polygon
				(pts
					(xy 102.78364 -72.873616) (xy 103.54564 -72.873616) (xy 103.54564 -72.365616) (xy 102.78364 -72.365616)
				)
			)
		)
	)
	(footprint ""
		(layer "F.Cu")
		(at 348.6658 -101.3714 90)
		(property "Reference" "C7C17"
			(at 0 0 90)
			(layer "F.SilkS")
			(hide yes)
			(effects
				(font
					(size 1.27 1.27)
				)
			)
		)
		(property "Value" ""
			(at 0 0 90)
			(layer "F.Fab")
			(effects
				(font
					(size 1.27 1.27)
				)
			)
		)
		(duplicate_pad_numbers_are_jumpers no)
		(fp_poly
			(pts
				(xy 0.3048 -0.1016) (xy 0.3048 0.9906) (xy -0.3048 0.9906) (xy -0.3048 -0.1016)
			)
			(stroke
				(width 0)
				(type default)
			)
			(fill no)
			(layer "F.CrtYd")
		)
		(fp_line
			(start 0.3048 -0.1016)
			(end -0.3048 -0.1016)
			(stroke
				(width 0.1)
				(type default)
			)
			(layer "F.Fab")
		)
		(fp_line
			(start -0.3048 -0.1016)
			(end -0.3048 0.9906)
			(stroke
				(width 0.1)
				(type default)
			)
			(layer "F.Fab")
		)
		(fp_line
			(start 0.3048 0.9906)
			(end 0.3048 -0.1016)
			(stroke
				(width 0.1)
				(type default)
			)
			(layer "F.Fab")
		)
		(fp_line
			(start -0.3048 0.9906)
			(end 0.3048 0.9906)
			(stroke
				(width 0.1)
				(type default)
			)
			(layer "F.Fab")
		)
		(pad "1" smd rect
			(at 0 0 90)
			(size 0.508 0.508)
			(layers "F.Cu" "F.Mask" "F.Paste")
			(net "VR_PVCCIO_CPU0_PH1_VCIN")
		)
		(pad "2" smd rect
			(at 0 0.889 90)
			(size 0.508 0.508)
			(layers "F.Cu" "F.Mask" "F.Paste")
			(net "GND")
		)
		(zone
			(layer "F.Cu")
			(hatch none 0.5)
			(connect_pads
				(clearance 0)
			)
			(min_thickness 0.25)
			(keepout
				(tracks allowed)
				(vias not_allowed)
				(pads allowed)
				(copperpour not_allowed)
				(footprints allowed)
			)
			(placement
				(enabled no)
				(sheetname "")
			)
			(fill
				(thermal_gap 0.5)
				(thermal_bridge_width 0.5)
				(island_removal_mode 0)
			)
			(polygon
				(pts
					(xy 348.9198 -101.1174) (xy 348.9198 -101.6254) (xy 349.3008 -101.6254) (xy 349.3008 -101.1174)
				)
			)
		)
		(zone
			(layer "F.Cu")
			(hatch none 0.5)
			(connect_pads
				(clearance 0)
			)
			(min_thickness 0.25)
			(keepout
				(tracks not_allowed)
				(vias allowed)
				(pads allowed)
				(copperpour not_allowed)
				(footprints allowed)
			)
			(placement
				(enabled no)
				(sheetname "")
			)
			(fill
				(thermal_gap 0.5)
				(thermal_bridge_width 0.5)
				(island_removal_mode 0)
			)
			(polygon
				(pts
					(xy 349.3008 -101.1174) (xy 349.3008 -101.6254) (xy 348.9198 -101.6254) (xy 348.9198 -101.1174)
				)
			)
		)
	)
	(footprint ""
		(layer "F.Cu")
		(at 316.73038 -34.936938 90)
		(property "Reference" "R6W29"
			(at -0.8382 -0.67818 90)
			(unlocked yes)
			(layer "F.SilkS")
			(effects
				(font
					(size 0.4064 0.254)
					(thickness 0.1524)
				)
				(justify left)
			)
		)
		(property "Value" ""
			(at 0 0 90)
			(layer "F.Fab")
			(effects
				(font
					(size 1.27 1.27)
				)
			)
		)
		(duplicate_pad_numbers_are_jumpers no)
		(fp_poly
			(pts
				(xy -0.2794 -0.1016) (xy 0.2794 -0.1016) (xy 0.2794 0.9906) (xy -0.2794 0.9906)
			)
			(stroke
				(width 0)
				(type default)
			)
			(fill no)
			(layer "F.CrtYd")
		)
		(fp_line
			(start 0.2794 -0.1016)
			(end -0.2794 -0.1016)
			(stroke
				(width 0.1)
				(type default)
			)
			(layer "F.Fab")
		)
		(fp_line
			(start -0.2794 -0.1016)
			(end -0.2794 0.9906)
			(stroke
				(width 0.1)
				(type default)
			)
			(layer "F.Fab")
		)
		(fp_line
			(start 0.2794 0.9906)
			(end 0.2794 -0.1016)
			(stroke
				(width 0.1)
				(type default)
			)
			(layer "F.Fab")
		)
		(fp_line
			(start -0.2794 0.9906)
			(end 0.2794 0.9906)
			(stroke
				(width 0.1)
				(type default)
			)
			(layer "F.Fab")
		)
		(pad "1" smd rect
			(at 0 0 90)
			(size 0.508 0.508)
			(layers "F.Cu" "F.Mask" "F.Paste")
			(net "PVPP_ABC")
		)
		(pad "2" smd rect
			(at 0 0.889 90)
			(size 0.508 0.508)
			(layers "F.Cu" "F.Mask" "F.Paste")
			(net "FM_ADR_COMPLETE_CPU1_N")
		)
		(zone
			(layer "F.Cu")
			(hatch none 0.5)
			(connect_pads
				(clearance 0)
			)
			(min_thickness 0.25)
			(keepout
				(tracks allowed)
				(vias not_allowed)
				(pads allowed)
				(copperpour not_allowed)
				(footprints allowed)
			)
			(placement
				(enabled no)
				(sheetname "")
			)
			(fill
				(thermal_gap 0.5)
				(thermal_bridge_width 0.5)
				(island_removal_mode 0)
			)
			(polygon
				(pts
					(xy 316.98438 -34.682938) (xy 316.98438 -35.190938) (xy 317.36538 -35.190938) (xy 317.36538 -34.682938)
				)
			)
		)
		(zone
			(layer "F.Cu")
			(hatch none 0.5)
			(connect_pads
				(clearance 0)
			)
			(min_thickness 0.25)
			(keepout
				(tracks not_allowed)
				(vias allowed)
				(pads allowed)
				(copperpour not_allowed)
				(footprints allowed)
			)
			(placement
				(enabled no)
				(sheetname "")
			)
			(fill
				(thermal_gap 0.5)
				(thermal_bridge_width 0.5)
				(island_removal_mode 0)
			)
			(polygon
				(pts
					(xy 317.36538 -34.682938) (xy 317.36538 -35.190938) (xy 316.98438 -35.190938) (xy 316.98438 -34.682938)
				)
			)
		)
	)
)
